(kicad_pcb
	(version 20260206)
	(generator "pcbnew")
	(generator_version "10.0")
	(general
		(thickness 1.6)
		(legacy_teardrops no)
	)
	(paper "A4")
	(title_block
		(title "01162023_DA0F0TEBIF0_F0T_Expander_BD_F_brd_V02_OCP.brd")
		(comment 1 "Grand Teton / footprints 5043-5049 of 9728")
	)
	(layers
		(0 "F.Cu" signal "TOP")
		(4 "In1.Cu" signal "GND")
		(6 "In2.Cu" signal "VCC")
		(8 "In3.Cu" signal "VCC1")
		(10 "In4.Cu" signal "GND1")
		(12 "In5.Cu" signal "IN1")
		(14 "In6.Cu" signal "GND2")
		(16 "In7.Cu" signal "IN2")
		(18 "In8.Cu" signal "GND3")
		(20 "In9.Cu" signal "IN3")
		(22 "In10.Cu" signal "GND4")
		(24 "In11.Cu" signal "IN4")
		(26 "In12.Cu" signal "GND5")
		(28 "In13.Cu" signal "IN5")
		(30 "In14.Cu" signal "GND6")
		(32 "In15.Cu" signal "IN6")
		(34 "In16.Cu" signal "GND7")
		(2 "B.Cu" signal "BOTTOM")
		(9 "F.Adhes" user "F.Adhesive")
		(11 "B.Adhes" user "B.Adhesive")
		(13 "F.Paste" user "Package Geometry/Pastemask Top")
		(15 "B.Paste" user "Package Geometry/Pastemask Bottom")
		(5 "F.SilkS" user "Ref Des/Silkscreen Top")
		(7 "B.SilkS" user "Ref Des/Silkscreen Bottom")
		(1 "F.Mask" user "Board Geometry/Soldermask Top")
		(3 "B.Mask" user "Board Geometry/Soldermask Bottom")
		(17 "Dwgs.User" user "User.Drawings")
		(19 "Cmts.User" user "User.Comments")
		(21 "Eco1.User" user "User.Eco1")
		(23 "Eco2.User" user "User.Eco2")
		(25 "Edge.Cuts" user "Board Geometry/Outline")
		(27 "Margin" user)
		(31 "F.CrtYd" user "Package Geometry/Place Bound Top")
		(29 "B.CrtYd" user "Package Geometry/Place Bound Bottom")
		(35 "F.Fab" user "Ref Des/Assembly Top")
		(33 "B.Fab" user "Ref Des/Assembly Bottom")
	)
	(footprint ""
		(layer "F.Cu")
		(at 312.739532 -159.235648 180)
		(property "Reference" "R297"
			(at 0 0 180)
			(layer "F.SilkS")
			(hide yes)
			(effects
				(font
					(size 1.27 1.27)
				)
			)
		)
		(property "Value" ""
			(at 0 0 180)
			(layer "F.Fab")
			(effects
				(font
					(size 1.27 1.27)
				)
			)
		)
		(duplicate_pad_numbers_are_jumpers no)
		(fp_line
			(start 0.7874 0.4064)
			(end -0.7874 0.4064)
			(stroke
				(width 0.1524)
				(type default)
			)
			(layer "F.SilkS")
		)
		(fp_line
			(start 0.7874 -0.4064)
			(end 0.7874 0.4064)
			(stroke
				(width 0.1524)
				(type default)
			)
			(layer "F.SilkS")
		)
		(fp_line
			(start -0.7874 0.4064)
			(end -0.7874 -0.4064)
			(stroke
				(width 0.1524)
				(type default)
			)
			(layer "F.SilkS")
		)
		(fp_line
			(start -0.7874 -0.4064)
			(end 0.7874 -0.4064)
			(stroke
				(width 0.1524)
				(type default)
			)
			(layer "F.SilkS")
		)
		(fp_line
			(start 0.67945 0.3048)
			(end 0.120396 0.3048)
			(stroke
				(width 0.1)
				(type default)
			)
			(layer "F.Fab")
		)
		(fp_line
			(start 0.67945 -0.3048)
			(end 0.67945 0.3048)
			(stroke
				(width 0.1)
				(type default)
			)
			(layer "F.Fab")
		)
		(fp_line
			(start 0.12065 -0.2794)
			(end 0.12065 -0.3048)
			(stroke
				(width 0.1)
				(type default)
			)
			(layer "F.Fab")
		)
		(fp_line
			(start 0.12065 -0.3048)
			(end 0.67945 -0.3048)
			(stroke
				(width 0.1)
				(type default)
			)
			(layer "F.Fab")
		)
		(fp_line
			(start 0.120396 0.3048)
			(end 0.120396 0.2794)
			(stroke
				(width 0.1)
				(type default)
			)
			(layer "F.Fab")
		)
		(fp_line
			(start 0.120396 0.2794)
			(end -0.12065 0.2794)
			(stroke
				(width 0.1)
				(type default)
			)
			(layer "F.Fab")
		)
		(fp_line
			(start -0.12065 0.3048)
			(end -0.67945 0.3048)
			(stroke
				(width 0.1)
				(type default)
			)
			(layer "F.Fab")
		)
		(fp_line
			(start -0.12065 0.2794)
			(end -0.12065 0.3048)
			(stroke
				(width 0.1)
				(type default)
			)
			(layer "F.Fab")
		)
		(fp_line
			(start -0.12065 -0.2794)
			(end 0.12065 -0.2794)
			(stroke
				(width 0.1)
				(type default)
			)
			(layer "F.Fab")
		)
		(fp_line
			(start -0.12065 -0.305054)
			(end -0.12065 -0.2794)
			(stroke
				(width 0.1)
				(type default)
			)
			(layer "F.Fab")
		)
		(fp_line
			(start -0.67945 0.3048)
			(end -0.67945 -0.305054)
			(stroke
				(width 0.1)
				(type default)
			)
			(layer "F.Fab")
		)
		(fp_line
			(start -0.67945 -0.305054)
			(end -0.12065 -0.305054)
			(stroke
				(width 0.1)
				(type default)
			)
			(layer "F.Fab")
		)
		(pad "1" smd circle
			(at -0.40005 0 180)
			(size 0 0)
			(layers "F.Cu" "F.Mask" "F.Paste")
			(net "PRSNT_NIC5_N")
		)
		(pad "2" smd circle
			(at 0.40005 0 180)
			(size 0 0)
			(layers "F.Cu" "F.Mask" "F.Paste")
			(net "PRSNTB3_NIC5_N")
		)
	)
	(footprint ""
		(layer "F.Cu")
		(at 337.206336 -198.27367 90)
		(property "Reference" "C2146"
			(at 0 0 90)
			(layer "F.SilkS")
			(hide yes)
			(effects
				(font
					(size 1.27 1.27)
				)
			)
		)
		(property "Value" ""
			(at 0 0 90)
			(layer "F.Fab")
			(effects
				(font
					(size 1.27 1.27)
				)
			)
		)
		(duplicate_pad_numbers_are_jumpers no)
		(fp_line
			(start 0.7874 -0.4064)
			(end 0.7874 0.4064)
			(stroke
				(width 0.1524)
				(type default)
			)
			(layer "F.SilkS")
		)
		(fp_line
			(start -0.7874 -0.4064)
			(end 0.7874 -0.4064)
			(stroke
				(width 0.1524)
				(type default)
			)
			(layer "F.SilkS")
		)
		(fp_line
			(start 0.7874 0.4064)
			(end -0.7874 0.4064)
			(stroke
				(width 0.1524)
				(type default)
			)
			(layer "F.SilkS")
		)
		(fp_line
			(start -0.7874 0.4064)
			(end -0.7874 -0.4064)
			(stroke
				(width 0.1524)
				(type default)
			)
			(layer "F.SilkS")
		)
		(fp_line
			(start -0.12065 -0.305054)
			(end -0.12065 -0.2794)
			(stroke
				(width 0.1)
				(type default)
			)
			(layer "F.Fab")
		)
		(fp_line
			(start -0.67945 -0.305054)
			(end -0.12065 -0.305054)
			(stroke
				(width 0.1)
				(type default)
			)
			(layer "F.Fab")
		)
		(fp_line
			(start 0.67945 -0.3048)
			(end 0.67945 0.3048)
			(stroke
				(width 0.1)
				(type default)
			)
			(layer "F.Fab")
		)
		(fp_line
			(start 0.12065 -0.3048)
			(end 0.67945 -0.3048)
			(stroke
				(width 0.1)
				(type default)
			)
			(layer "F.Fab")
		)
		(fp_line
			(start 0.12065 -0.2794)
			(end 0.12065 -0.3048)
			(stroke
				(width 0.1)
				(type default)
			)
			(layer "F.Fab")
		)
		(fp_line
			(start -0.12065 -0.2794)
			(end 0.12065 -0.2794)
			(stroke
				(width 0.1)
				(type default)
			)
			(layer "F.Fab")
		)
		(fp_line
			(start 0.120396 0.2794)
			(end -0.12065 0.2794)
			(stroke
				(width 0.1)
				(type default)
			)
			(layer "F.Fab")
		)
		(fp_line
			(start -0.12065 0.2794)
			(end -0.12065 0.3048)
			(stroke
				(width 0.1)
				(type default)
			)
			(layer "F.Fab")
		)
		(fp_line
			(start 0.67945 0.3048)
			(end 0.120396 0.3048)
			(stroke
				(width 0.1)
				(type default)
			)
			(layer "F.Fab")
		)
		(fp_line
			(start 0.120396 0.3048)
			(end 0.120396 0.2794)
			(stroke
				(width 0.1)
				(type default)
			)
			(layer "F.Fab")
		)
		(fp_line
			(start -0.12065 0.3048)
			(end -0.67945 0.3048)
			(stroke
				(width 0.1)
				(type default)
			)
			(layer "F.Fab")
		)
		(fp_line
			(start -0.67945 0.3048)
			(end -0.67945 -0.305054)
			(stroke
				(width 0.1)
				(type default)
			)
			(layer "F.Fab")
		)
		(pad "1" smd circle
			(at -0.40005 0 90)
			(size 0 0)
			(layers "F.Cu" "F.Mask" "F.Paste")
			(net "P3V3_AUX")
		)
		(pad "2" smd circle
			(at 0.40005 0 90)
			(size 0 0)
			(layers "F.Cu" "F.Mask" "F.Paste")
			(net "GND")
		)
	)
	(footprint ""
		(layer "F.Cu")
		(at 236.382814 -285.911544 180)
		(property "Reference" "PC258"
			(at 0 0 180)
			(layer "F.SilkS")
			(hide yes)
			(effects
				(font
					(size 1.27 1.27)
				)
			)
		)
		(property "Value" ""
			(at 0 0 180)
			(layer "F.Fab")
			(effects
				(font
					(size 1.27 1.27)
				)
			)
		)
		(duplicate_pad_numbers_are_jumpers no)
		(fp_line
			(start 2.750058 2.750058)
			(end 2.750058 0.9398)
			(stroke
				(width 0.1524)
				(type default)
			)
			(layer "F.SilkS")
		)
		(fp_line
			(start 2.750058 -0.9398)
			(end 2.750058 -2.750058)
			(stroke
				(width 0.1524)
				(type default)
			)
			(layer "F.SilkS")
		)
		(fp_line
			(start 2.750058 -2.750058)
			(end -1.988058 -2.750058)
			(stroke
				(width 0.1524)
				(type default)
			)
			(layer "F.SilkS")
		)
		(fp_line
			(start -1.988058 2.750058)
			(end 2.750058 2.750058)
			(stroke
				(width 0.1524)
				(type default)
			)
			(layer "F.SilkS")
		)
		(fp_line
			(start -1.988058 -2.750058)
			(end -2.750058 -1.988058)
			(stroke
				(width 0.1524)
				(type default)
			)
			(layer "F.SilkS")
		)
		(fp_line
			(start -2.750058 1.988058)
			(end -1.988058 2.750058)
			(stroke
				(width 0.1524)
				(type default)
			)
			(layer "F.SilkS")
		)
		(fp_line
			(start -2.750058 0.9398)
			(end -2.750058 1.988058)
			(stroke
				(width 0.1524)
				(type default)
			)
			(layer "F.SilkS")
		)
		(fp_line
			(start -2.750058 -1.988058)
			(end -2.750058 -0.9398)
			(stroke
				(width 0.1524)
				(type default)
			)
			(layer "F.SilkS")
		)
		(fp_line
			(start 2.750058 2.750058)
			(end 2.750058 -2.750058)
			(stroke
				(width 0.1)
				(type default)
			)
			(layer "F.Fab")
		)
		(fp_line
			(start 2.750058 -2.750058)
			(end -2.750058 -2.750058)
			(stroke
				(width 0.1)
				(type default)
			)
			(layer "F.Fab")
		)
		(fp_line
			(start -2.750058 2.750058)
			(end 2.750058 2.750058)
			(stroke
				(width 0.1)
				(type default)
			)
			(layer "F.Fab")
		)
		(fp_line
			(start -2.750058 -2.750058)
			(end -2.750058 2.750058)
			(stroke
				(width 0.1)
				(type default)
			)
			(layer "F.Fab")
		)
		(pad "1" smd rect
			(at -2.199894 0 270)
			(size 1.6002 3.0226)
			(layers "F.Cu" "F.Mask" "F.Paste")
			(net "P1V25_PEX2_R")
		)
		(pad "2" smd rect
			(at 2.199894 0 270)
			(size 1.6002 3.0226)
			(layers "F.Cu" "F.Mask" "F.Paste")
			(net "GND")
		)
	)
	(footprint ""
		(layer "F.Cu")
		(at 242.310412 -124.963428 180)
		(property "Reference" "R4475"
			(at 0 0 180)
			(layer "F.SilkS")
			(hide yes)
			(effects
				(font
					(size 1.27 1.27)
				)
			)
		)
		(property "Value" ""
			(at 0 0 180)
			(layer "F.Fab")
			(effects
				(font
					(size 1.27 1.27)
				)
			)
		)
		(duplicate_pad_numbers_are_jumpers no)
		(fp_line
			(start 0.7874 0.4064)
			(end -0.7874 0.4064)
			(stroke
				(width 0.1524)
				(type default)
			)
			(layer "F.SilkS")
		)
		(fp_line
			(start 0.7874 -0.4064)
			(end 0.7874 0.4064)
			(stroke
				(width 0.1524)
				(type default)
			)
			(layer "F.SilkS")
		)
		(fp_line
			(start -0.7874 0.4064)
			(end -0.7874 -0.4064)
			(stroke
				(width 0.1524)
				(type default)
			)
			(layer "F.SilkS")
		)
		(fp_line
			(start -0.7874 -0.4064)
			(end 0.7874 -0.4064)
			(stroke
				(width 0.1524)
				(type default)
			)
			(layer "F.SilkS")
		)
		(fp_line
			(start 0.67945 0.3048)
			(end 0.120396 0.3048)
			(stroke
				(width 0.1)
				(type default)
			)
			(layer "F.Fab")
		)
		(fp_line
			(start 0.67945 -0.3048)
			(end 0.67945 0.3048)
			(stroke
				(width 0.1)
				(type default)
			)
			(layer "F.Fab")
		)
		(fp_line
			(start 0.12065 -0.2794)
			(end 0.12065 -0.3048)
			(stroke
				(width 0.1)
				(type default)
			)
			(layer "F.Fab")
		)
		(fp_line
			(start 0.12065 -0.3048)
			(end 0.67945 -0.3048)
			(stroke
				(width 0.1)
				(type default)
			)
			(layer "F.Fab")
		)
		(fp_line
			(start 0.120396 0.3048)
			(end 0.120396 0.2794)
			(stroke
				(width 0.1)
				(type default)
			)
			(layer "F.Fab")
		)
		(fp_line
			(start 0.120396 0.2794)
			(end -0.12065 0.2794)
			(stroke
				(width 0.1)
				(type default)
			)
			(layer "F.Fab")
		)
		(fp_line
			(start -0.12065 0.3048)
			(end -0.67945 0.3048)
			(stroke
				(width 0.1)
				(type default)
			)
			(layer "F.Fab")
		)
		(fp_line
			(start -0.12065 0.2794)
			(end -0.12065 0.3048)
			(stroke
				(width 0.1)
				(type default)
			)
			(layer "F.Fab")
		)
		(fp_line
			(start -0.12065 -0.2794)
			(end 0.12065 -0.2794)
			(stroke
				(width 0.1)
				(type default)
			)
			(layer "F.Fab")
		)
		(fp_line
			(start -0.12065 -0.305054)
			(end -0.12065 -0.2794)
			(stroke
				(width 0.1)
				(type default)
			)
			(layer "F.Fab")
		)
		(fp_line
			(start -0.67945 0.3048)
			(end -0.67945 -0.305054)
			(stroke
				(width 0.1)
				(type default)
			)
			(layer "F.Fab")
		)
		(fp_line
			(start -0.67945 -0.305054)
			(end -0.12065 -0.305054)
			(stroke
				(width 0.1)
				(type default)
			)
			(layer "F.Fab")
		)
		(pad "1" smd circle
			(at -0.40005 0 180)
			(size 0 0)
			(layers "F.Cu" "F.Mask" "F.Paste")
			(net "PWRGD_P3V3_NIC4")
		)
		(pad "2" smd circle
			(at 0.40005 0 180)
			(size 0 0)
			(layers "F.Cu" "F.Mask" "F.Paste")
			(net "PWRGD_P3V3_NIC4_R")
		)
	)
	(footprint ""
		(layer "F.Cu")
		(at 115.38966 -159.377126 -90)
		(property "Reference" "PJ3"
			(at 0 0 270)
			(layer "F.SilkS")
			(hide yes)
			(effects
				(font
					(size 1.27 1.27)
				)
			)
		)
		(property "Value" ""
			(at 0 0 270)
			(layer "F.Fab")
			(effects
				(font
					(size 1.27 1.27)
				)
			)
		)
		(duplicate_pad_numbers_are_jumpers no)
		(pad "1" smd circle
			(at -0.40005 0)
			(size 0 0)
			(layers "F.Cu" "F.Mask" "F.Paste")
			(net "SH_P3V3_AUX_FB")
		)
		(pad "2" smd rect
			(at 0.40005 0 90)
			(size 0.4572 0.508)
			(layers "F.Cu" "F.Mask" "F.Paste")
			(net "P3V3_AUX")
		)
		(zone
			(layer "F.Cu")
			(hatch none 0.5)
			(connect_pads
				(clearance 0)
			)
			(min_thickness 0.25)
			(keepout
				(tracks allowed)
				(vias not_allowed)
				(pads allowed)
				(copperpour not_allowed)
				(footprints allowed)
			)
			(placement
				(enabled no)
				(sheetname "")
			)
			(fill
				(thermal_gap 0.5)
				(thermal_bridge_width 0.5)
				(island_removal_mode 0)
			)
			(polygon
				(pts
					(xy 115.08486 -158.691326) (xy 115.69446 -158.691326) (xy 115.69446 -160.062926) (xy 115.08486 -160.062926)
				)
			)
		)
	)
	(footprint ""
		(layer "F.Cu")
		(at 381.254 -195.326 180)
		(property "Reference" "R4678"
			(at 0 0 180)
			(layer "F.SilkS")
			(hide yes)
			(effects
				(font
					(size 1.27 1.27)
				)
			)
		)
		(property "Value" ""
			(at 0 0 180)
			(layer "F.Fab")
			(effects
				(font
					(size 1.27 1.27)
				)
			)
		)
		(duplicate_pad_numbers_are_jumpers no)
		(fp_line
			(start 0.7874 0.4064)
			(end -0.7874 0.4064)
			(stroke
				(width 0.1524)
				(type default)
			)
			(layer "F.SilkS")
		)
		(fp_line
			(start 0.7874 -0.4064)
			(end 0.7874 0.4064)
			(stroke
				(width 0.1524)
				(type default)
			)
			(layer "F.SilkS")
		)
		(fp_line
			(start -0.7874 0.4064)
			(end -0.7874 -0.4064)
			(stroke
				(width 0.1524)
				(type default)
			)
			(layer "F.SilkS")
		)
		(fp_line
			(start -0.7874 -0.4064)
			(end 0.7874 -0.4064)
			(stroke
				(width 0.1524)
				(type default)
			)
			(layer "F.SilkS")
		)
		(fp_line
			(start 0.67945 0.3048)
			(end 0.120396 0.3048)
			(stroke
				(width 0.1)
				(type default)
			)
			(layer "F.Fab")
		)
		(fp_line
			(start 0.67945 -0.3048)
			(end 0.67945 0.3048)
			(stroke
				(width 0.1)
				(type default)
			)
			(layer "F.Fab")
		)
		(fp_line
			(start 0.12065 -0.2794)
			(end 0.12065 -0.3048)
			(stroke
				(width 0.1)
				(type default)
			)
			(layer "F.Fab")
		)
		(fp_line
			(start 0.12065 -0.3048)
			(end 0.67945 -0.3048)
			(stroke
				(width 0.1)
				(type default)
			)
			(layer "F.Fab")
		)
		(fp_line
			(start 0.120396 0.3048)
			(end 0.120396 0.2794)
			(stroke
				(width 0.1)
				(type default)
			)
			(layer "F.Fab")
		)
		(fp_line
			(start 0.120396 0.2794)
			(end -0.12065 0.2794)
			(stroke
				(width 0.1)
				(type default)
			)
			(layer "F.Fab")
		)
		(fp_line
			(start -0.12065 0.3048)
			(end -0.67945 0.3048)
			(stroke
				(width 0.1)
				(type default)
			)
			(layer "F.Fab")
		)
		(fp_line
			(start -0.12065 0.2794)
			(end -0.12065 0.3048)
			(stroke
				(width 0.1)
				(type default)
			)
			(layer "F.Fab")
		)
		(fp_line
			(start -0.12065 -0.2794)
			(end 0.12065 -0.2794)
			(stroke
				(width 0.1)
				(type default)
			)
			(layer "F.Fab")
		)
		(fp_line
			(start -0.12065 -0.305054)
			(end -0.12065 -0.2794)
			(stroke
				(width 0.1)
				(type default)
			)
			(layer "F.Fab")
		)
		(fp_line
			(start -0.67945 0.3048)
			(end -0.67945 -0.305054)
			(stroke
				(width 0.1)
				(type default)
			)
			(layer "F.Fab")
		)
		(fp_line
			(start -0.67945 -0.305054)
			(end -0.12065 -0.305054)
			(stroke
				(width 0.1)
				(type default)
			)
			(layer "F.Fab")
		)
		(pad "1" smd circle
			(at -0.40005 0 180)
			(size 0 0)
			(layers "F.Cu" "F.Mask" "F.Paste")
			(net "NIC2_PEX_PWR_EN_R")
		)
		(pad "2" smd circle
			(at 0.40005 0 180)
			(size 0 0)
			(layers "F.Cu" "F.Mask" "F.Paste")
			(net "GND")
		)
	)
	(footprint ""
		(layer "F.Cu")
		(at 219.223844 -98.806 -90)
		(property "Reference" "R717"
			(at 0 0 270)
			(layer "F.SilkS")
			(hide yes)
			(effects
				(font
					(size 1.27 1.27)
				)
			)
		)
		(property "Value" ""
			(at 0 0 270)
			(layer "F.Fab")
			(effects
				(font
					(size 1.27 1.27)
				)
			)
		)
		(duplicate_pad_numbers_are_jumpers no)
		(fp_line
			(start -0.7874 0.4064)
			(end -0.7874 -0.4064)
			(stroke
				(width 0.1524)
				(type default)
			)
			(layer "F.SilkS")
		)
		(fp_line
			(start 0.7874 0.4064)
			(end -0.7874 0.4064)
			(stroke
				(width 0.1524)
				(type default)
			)
			(layer "F.SilkS")
		)
		(fp_line
			(start -0.7874 -0.4064)
			(end 0.7874 -0.4064)
			(stroke
				(width 0.1524)
				(type default)
			)
			(layer "F.SilkS")
		)
		(fp_line
			(start 0.7874 -0.4064)
			(end 0.7874 0.4064)
			(stroke
				(width 0.1524)
				(type default)
			)
			(layer "F.SilkS")
		)
		(fp_line
			(start -0.67945 0.3048)
			(end -0.67945 -0.305054)
			(stroke
				(width 0.1)
				(type default)
			)
			(layer "F.Fab")
		)
		(fp_line
			(start -0.12065 0.3048)
			(end -0.67945 0.3048)
			(stroke
				(width 0.1)
				(type default)
			)
			(layer "F.Fab")
		)
		(fp_line
			(start 0.120396 0.3048)
			(end 0.120396 0.2794)
			(stroke
				(width 0.1)
				(type default)
			)
			(layer "F.Fab")
		)
		(fp_line
			(start 0.67945 0.3048)
			(end 0.120396 0.3048)
			(stroke
				(width 0.1)
				(type default)
			)
			(layer "F.Fab")
		)
		(fp_line
			(start -0.12065 0.2794)
			(end -0.12065 0.3048)
			(stroke
				(width 0.1)
				(type default)
			)
			(layer "F.Fab")
		)
		(fp_line
			(start 0.120396 0.2794)
			(end -0.12065 0.2794)
			(stroke
				(width 0.1)
				(type default)
			)
			(layer "F.Fab")
		)
		(fp_line
			(start -0.12065 -0.2794)
			(end 0.12065 -0.2794)
			(stroke
				(width 0.1)
				(type default)
			)
			(layer "F.Fab")
		)
		(fp_line
			(start 0.12065 -0.2794)
			(end 0.12065 -0.3048)
			(stroke
				(width 0.1)
				(type default)
			)
			(layer "F.Fab")
		)
		(fp_line
			(start 0.12065 -0.3048)
			(end 0.67945 -0.3048)
			(stroke
				(width 0.1)
				(type default)
			)
			(layer "F.Fab")
		)
		(fp_line
			(start 0.67945 -0.3048)
			(end 0.67945 0.3048)
			(stroke
				(width 0.1)
				(type default)
			)
			(layer "F.Fab")
		)
		(fp_line
			(start -0.67945 -0.305054)
			(end -0.12065 -0.305054)
			(stroke
				(width 0.1)
				(type default)
			)
			(layer "F.Fab")
		)
		(fp_line
			(start -0.12065 -0.305054)
			(end -0.12065 -0.2794)
			(stroke
				(width 0.1)
				(type default)
			)
			(layer "F.Fab")
		)
		(pad "1" smd circle
			(at -0.40005 0 270)
			(size 0 0)
			(layers "F.Cu" "F.Mask" "F.Paste")
			(net "NIC3_ADC_ALERT_N")
		)
		(pad "2" smd circle
			(at 0.40005 0 270)
			(size 0 0)
			(layers "F.Cu" "F.Mask" "F.Paste")
			(net "NIC_ADC_ALERT_N")
		)
	)
)
